(kicad_pcb
	(version 20260206)
	(generator "pcbnew")
	(generator_version "10.0")
	(general
		(thickness 1.6)
		(legacy_teardrops no)
	)
	(paper "A4")
	(title_block
		(title "03242023_DA0F0TMBIJ0_F0T_Motherboard_J_brd_V01_OCP.brd")
		(comment 1 "Grand Teton / footprints 2072-2076 of 6105")
	)
	(layers
		(0 "F.Cu" signal "TOP")
		(4 "In1.Cu" signal "GND")
		(6 "In2.Cu" signal "IN1")
		(8 "In3.Cu" signal "GND1")
		(10 "In4.Cu" signal "IN2")
		(12 "In5.Cu" signal "GND2")
		(14 "In6.Cu" signal "IN3")
		(16 "In7.Cu" signal "GND3")
		(18 "In8.Cu" signal "VCC")
		(20 "In9.Cu" signal "VCC1")
		(22 "In10.Cu" signal "GND4")
		(24 "In11.Cu" signal "IN4")
		(26 "In12.Cu" signal "GND5")
		(28 "In13.Cu" signal "IN5")
		(30 "In14.Cu" signal "GND6")
		(32 "In15.Cu" signal "IN6")
		(34 "In16.Cu" signal "GND7")
		(2 "B.Cu" signal "BOTTOM")
		(9 "F.Adhes" user "F.Adhesive")
		(11 "B.Adhes" user "B.Adhesive")
		(13 "F.Paste" user "Package Geometry/Pastemask Top")
		(15 "B.Paste" user "Package Geometry/Pastemask Bottom")
		(5 "F.SilkS" user "Ref Des/Silkscreen Top")
		(7 "B.SilkS" user "Ref Des/Silkscreen Bottom")
		(1 "F.Mask" user "Board Geometry/Soldermask Top")
		(3 "B.Mask" user "Board Geometry/Soldermask Bottom")
		(17 "Dwgs.User" user "User.Drawings")
		(19 "Cmts.User" user "User.Comments")
		(21 "Eco1.User" user "User.Eco1")
		(23 "Eco2.User" user "User.Eco2")
		(25 "Edge.Cuts" user "Board Geometry/Outline")
		(27 "Margin" user)
		(31 "F.CrtYd" user "Package Geometry/Place Bound Top")
		(29 "B.CrtYd" user "Package Geometry/Place Bound Bottom")
		(35 "F.Fab" user "Ref Des/Assembly Top")
		(33 "B.Fab" user "Ref Des/Assembly Bottom")
	)
	(footprint ""
		(layer "F.Cu")
		(at 428.007526 -140.269214 180)
		(property "Reference" "PC215"
			(at 0 0 180)
			(layer "F.SilkS")
			(hide yes)
			(effects
				(font
					(size 1.27 1.27)
				)
			)
		)
		(property "Value" ""
			(at 0 0 180)
			(layer "F.Fab")
			(effects
				(font
					(size 1.27 1.27)
				)
			)
		)
		(duplicate_pad_numbers_are_jumpers no)
		(fp_line
			(start 0.7874 0.4064)
			(end -0.7874 0.4064)
			(stroke
				(width 0.1524)
				(type default)
			)
			(layer "F.SilkS")
		)
		(fp_line
			(start 0.7874 -0.4064)
			(end 0.7874 0.4064)
			(stroke
				(width 0.1524)
				(type default)
			)
			(layer "F.SilkS")
		)
		(fp_line
			(start -0.7874 0.4064)
			(end -0.7874 -0.4064)
			(stroke
				(width 0.1524)
				(type default)
			)
			(layer "F.SilkS")
		)
		(fp_line
			(start -0.7874 -0.4064)
			(end 0.7874 -0.4064)
			(stroke
				(width 0.1524)
				(type default)
			)
			(layer "F.SilkS")
		)
		(fp_line
			(start 0.67945 0.3048)
			(end 0.120396 0.3048)
			(stroke
				(width 0.1)
				(type default)
			)
			(layer "F.Fab")
		)
		(fp_line
			(start 0.67945 -0.3048)
			(end 0.67945 0.3048)
			(stroke
				(width 0.1)
				(type default)
			)
			(layer "F.Fab")
		)
		(fp_line
			(start 0.12065 -0.2794)
			(end 0.12065 -0.3048)
			(stroke
				(width 0.1)
				(type default)
			)
			(layer "F.Fab")
		)
		(fp_line
			(start 0.12065 -0.3048)
			(end 0.67945 -0.3048)
			(stroke
				(width 0.1)
				(type default)
			)
			(layer "F.Fab")
		)
		(fp_line
			(start 0.120396 0.3048)
			(end 0.120396 0.2794)
			(stroke
				(width 0.1)
				(type default)
			)
			(layer "F.Fab")
		)
		(fp_line
			(start 0.120396 0.2794)
			(end -0.12065 0.2794)
			(stroke
				(width 0.1)
				(type default)
			)
			(layer "F.Fab")
		)
		(fp_line
			(start -0.12065 0.3048)
			(end -0.67945 0.3048)
			(stroke
				(width 0.1)
				(type default)
			)
			(layer "F.Fab")
		)
		(fp_line
			(start -0.12065 0.2794)
			(end -0.12065 0.3048)
			(stroke
				(width 0.1)
				(type default)
			)
			(layer "F.Fab")
		)
		(fp_line
			(start -0.12065 -0.2794)
			(end 0.12065 -0.2794)
			(stroke
				(width 0.1)
				(type default)
			)
			(layer "F.Fab")
		)
		(fp_line
			(start -0.12065 -0.305054)
			(end -0.12065 -0.2794)
			(stroke
				(width 0.1)
				(type default)
			)
			(layer "F.Fab")
		)
		(fp_line
			(start -0.67945 0.3048)
			(end -0.67945 -0.305054)
			(stroke
				(width 0.1)
				(type default)
			)
			(layer "F.Fab")
		)
		(fp_line
			(start -0.67945 -0.305054)
			(end -0.12065 -0.305054)
			(stroke
				(width 0.1)
				(type default)
			)
			(layer "F.Fab")
		)
		(pad "1" smd circle
			(at -0.40005 0 180)
			(size 0 0)
			(layers "F.Cu" "F.Mask" "F.Paste")
			(net "SH_PVCCINFAON_CPU0_R")
		)
		(pad "2" smd circle
			(at 0.40005 0 180)
			(size 0 0)
			(layers "F.Cu" "F.Mask" "F.Paste")
			(net "VSENSE_PVCCINFAON_CPU0_DN")
		)
	)
	(footprint ""
		(layer "F.Cu")
		(at 363.62005 -355.985826 90)
		(property "Reference" "PJ53"
			(at -0.293878 1.27762 90)
			(unlocked yes)
			(layer "F.SilkS")
			(effects
				(font
					(size 0.7874 0.5842)
					(thickness 0.1524)
				)
				(justify left)
			)
		)
		(property "Value" ""
			(at 0 0 90)
			(layer "F.Fab")
			(effects
				(font
					(size 1.27 1.27)
				)
			)
		)
		(duplicate_pad_numbers_are_jumpers no)
		(pad "1" smd circle
			(at -0.7493 0 180)
			(size 0 0)
			(layers "F.Cu" "F.Mask" "F.Paste")
			(net "VSENSE_PVCCFA_EHV_FIVRA_CPU0_DP")
		)
		(pad "2" smd rect
			(at 0.7493 0)
			(size 0.7112 0.8128)
			(layers "F.Cu" "F.Mask" "F.Paste")
			(net "SH_PVCCFA_EHV_FIVRA_CPU0")
		)
		(zone
			(layer "F.Cu")
			(hatch none 0.5)
			(connect_pads
				(clearance 0)
			)
			(min_thickness 0.25)
			(keepout
				(tracks allowed)
				(vias not_allowed)
				(pads allowed)
				(copperpour not_allowed)
				(footprints allowed)
			)
			(placement
				(enabled no)
				(sheetname "")
			)
			(fill
				(thermal_gap 0.5)
				(thermal_bridge_width 0.5)
				(island_removal_mode 0)
			)
			(polygon
				(pts
					(xy 363.21365 -354.804726) (xy 364.031276 -354.804726) (xy 364.031276 -357.192326) (xy 363.21365 -357.192326)
				)
			)
		)
	)
	(footprint ""
		(layer "F.Cu")
		(at 120.908572 -133.971538)
		(property "Reference" "U36"
			(at -2.1844 -4.587748 0)
			(unlocked yes)
			(layer "F.SilkS")
			(effects
				(font
					(size 0.7874 0.5842)
					(thickness 0.1524)
				)
				(justify left)
			)
		)
		(property "Value" ""
			(at 0 0 0)
			(layer "F.Fab")
			(effects
				(font
					(size 1.27 1.27)
				)
			)
		)
		(duplicate_pad_numbers_are_jumpers no)
		(fp_line
			(start -1.8542 -3.949954)
			(end -1.8542 3.949954)
			(stroke
				(width 0.1524)
				(type default)
			)
			(layer "F.SilkS")
		)
		(fp_line
			(start -1.8542 3.949954)
			(end 1.8542 3.949954)
			(stroke
				(width 0.1524)
				(type default)
			)
			(layer "F.SilkS")
		)
		(fp_line
			(start -1.282954 -3.949954)
			(end -1.8542 -3.949954)
			(stroke
				(width 0.1524)
				(type default)
			)
			(layer "F.SilkS")
		)
		(fp_line
			(start 0 -2.667)
			(end -1.282954 -3.949954)
			(stroke
				(width 0.1524)
				(type default)
			)
			(layer "F.SilkS")
		)
		(fp_line
			(start 1.282954 -3.949954)
			(end 0 -2.667)
			(stroke
				(width 0.1524)
				(type default)
			)
			(layer "F.SilkS")
		)
		(fp_line
			(start 1.8542 -3.949954)
			(end 1.282954 -3.949954)
			(stroke
				(width 0.1524)
				(type default)
			)
			(layer "F.SilkS")
		)
		(fp_line
			(start 1.8542 3.949954)
			(end 1.8542 -3.949954)
			(stroke
				(width 0.1524)
				(type default)
			)
			(layer "F.SilkS")
		)
		(fp_poly
			(pts
				(xy -4.8006 -4.08305) (xy -4.8006 -3.06705) (xy -3.7846 -3.57505)
			)
			(stroke
				(width 0)
				(type default)
			)
			(fill yes)
			(layer "F.SilkS")
		)
		(fp_line
			(start -2.249932 -3.949954)
			(end -2.249932 3.949954)
			(stroke
				(width 0.1)
				(type default)
			)
			(layer "F.Fab")
		)
		(fp_line
			(start -2.249932 3.949954)
			(end 2.249932 3.949954)
			(stroke
				(width 0.1)
				(type default)
			)
			(layer "F.Fab")
		)
		(fp_line
			(start 2.249932 -3.949954)
			(end -2.249932 -3.949954)
			(stroke
				(width 0.1)
				(type default)
			)
			(layer "F.Fab")
		)
		(fp_line
			(start 2.249932 3.949954)
			(end 2.249932 -3.949954)
			(stroke
				(width 0.1)
				(type default)
			)
			(layer "F.Fab")
		)
		(fp_poly
			(pts
				(xy -4.8006 -4.08305) (xy -4.8006 -3.06705) (xy -3.7846 -3.57505)
			)
			(stroke
				(width 0)
				(type default)
			)
			(fill yes)
			(layer "F.Fab")
		)
		(pad "1" smd rect
			(at -2.800096 -3.57505 270)
			(size 0.3048 1.6002)
			(layers "F.Cu" "F.Mask" "F.Paste")
			(net "PCA9548_PCIE3_ADDR0")
		)
		(pad "2" smd rect
			(at -2.800096 -2.925064 270)
			(size 0.3048 1.6002)
			(layers "F.Cu" "F.Mask" "F.Paste")
			(net "PCA9548_PCIE3_ADDR1")
		)
		(pad "3" smd rect
			(at -2.800096 -2.275078 270)
			(size 0.3048 1.6002)
			(layers "F.Cu" "F.Mask" "F.Paste")
			(net "PU_RST_SMB_PCIE0_N")
		)
		(pad "4" smd rect
			(at -2.800096 -1.625092 270)
			(size 0.3048 1.6002)
			(layers "F.Cu" "F.Mask" "F.Paste")
			(net "Net_283")
		)
		(pad "5" smd rect
			(at -2.800096 -0.975106 270)
			(size 0.3048 1.6002)
			(layers "F.Cu" "F.Mask" "F.Paste")
			(net "Net_281")
		)
		(pad "6" smd rect
			(at -2.800096 -0.32512 270)
			(size 0.3048 1.6002)
			(layers "F.Cu" "F.Mask" "F.Paste")
			(net "SMB_IOEXP_3V3AUX_SDA_R")
		)
		(pad "7" smd rect
			(at -2.800096 0.32512 270)
			(size 0.3048 1.6002)
			(layers "F.Cu" "F.Mask" "F.Paste")
			(net "SMB_IOEXP_3V3AUX_SCL_R")
		)
		(pad "8" smd rect
			(at -2.800096 0.975106 270)
			(size 0.3048 1.6002)
			(layers "F.Cu" "F.Mask" "F.Paste")
			(net "SMB_PCIE0_3V3AUX_SDA_R3")
		)
		(pad "9" smd rect
			(at -2.800096 1.625092 270)
			(size 0.3048 1.6002)
			(layers "F.Cu" "F.Mask" "F.Paste")
			(net "SMB_PCIE0_3V3AUX_SCL_R3")
		)
		(pad "10" smd rect
			(at -2.800096 2.275078 270)
			(size 0.3048 1.6002)
			(layers "F.Cu" "F.Mask" "F.Paste")
			(net "SMB_PCIE0_3V3AUX_SDA_R5")
		)
		(pad "11" smd rect
			(at -2.800096 2.925064 270)
			(size 0.3048 1.6002)
			(layers "F.Cu" "F.Mask" "F.Paste")
			(net "SMB_PCIE0_3V3AUX_SCL_R5")
		)
		(pad "12" smd rect
			(at -2.800096 3.57505 270)
			(size 0.3048 1.6002)
			(layers "F.Cu" "F.Mask" "F.Paste")
			(net "GND")
		)
		(pad "13" smd rect
			(at 2.800096 3.57505 270)
			(size 0.3048 1.6002)
			(layers "F.Cu" "F.Mask" "F.Paste")
			(net "SMB_BMC_SWB_SDA_R4")
		)
		(pad "14" smd rect
			(at 2.800096 2.925064 270)
			(size 0.3048 1.6002)
			(layers "F.Cu" "F.Mask" "F.Paste")
			(net "SMB_BMC_SWB_SCL_R4")
		)
		(pad "15" smd rect
			(at 2.800096 2.275078 270)
			(size 0.3048 1.6002)
			(layers "F.Cu" "F.Mask" "F.Paste")
			(net "SMB_FRU_3V3AUX_SDA_R")
		)
		(pad "16" smd rect
			(at 2.800096 1.625092 270)
			(size 0.3048 1.6002)
			(layers "F.Cu" "F.Mask" "F.Paste")
			(net "SMB_FRU_3V3AUX_SCL_R")
		)
		(pad "17" smd rect
			(at 2.800096 0.975106 270)
			(size 0.3048 1.6002)
			(layers "F.Cu" "F.Mask" "F.Paste")
			(net "SMB_INA230_3V3AUX_SDA_R")
		)
		(pad "18" smd rect
			(at 2.800096 0.32512 270)
			(size 0.3048 1.6002)
			(layers "F.Cu" "F.Mask" "F.Paste")
			(net "SMB_INA230_3V3AUX_SCL_R")
		)
		(pad "19" smd rect
			(at 2.800096 -0.32512 270)
			(size 0.3048 1.6002)
			(layers "F.Cu" "F.Mask" "F.Paste")
			(net "Net_284")
		)
		(pad "20" smd rect
			(at 2.800096 -0.975106 270)
			(size 0.3048 1.6002)
			(layers "F.Cu" "F.Mask" "F.Paste")
			(net "Net_282")
		)
		(pad "21" smd rect
			(at 2.800096 -1.625092 270)
			(size 0.3048 1.6002)
			(layers "F.Cu" "F.Mask" "F.Paste")
			(net "PCA9548_PCIE3_ADDR2")
		)
		(pad "22" smd rect
			(at 2.800096 -2.275078 270)
			(size 0.3048 1.6002)
			(layers "F.Cu" "F.Mask" "F.Paste")
			(net "SMB_PCIE0_3V3AUX_SCL_R")
		)
		(pad "23" smd rect
			(at 2.800096 -2.925064 270)
			(size 0.3048 1.6002)
			(layers "F.Cu" "F.Mask" "F.Paste")
			(net "SMB_PCIE0_3V3AUX_SDA_R")
		)
		(pad "24" smd rect
			(at 2.800096 -3.57505 270)
			(size 0.3048 1.6002)
			(layers "F.Cu" "F.Mask" "F.Paste")
			(net "P3V3_AUX")
		)
	)
	(footprint ""
		(layer "F.Cu")
		(at 22.91588 -429.351948 180)
		(property "Reference" "R2918"
			(at 0 0 180)
			(layer "F.SilkS")
			(hide yes)
			(effects
				(font
					(size 1.27 1.27)
				)
			)
		)
		(property "Value" ""
			(at 0 0 180)
			(layer "F.Fab")
			(effects
				(font
					(size 1.27 1.27)
				)
			)
		)
		(duplicate_pad_numbers_are_jumpers no)
		(fp_line
			(start 0.7874 0.4064)
			(end -0.7874 0.4064)
			(stroke
				(width 0.1524)
				(type default)
			)
			(layer "F.SilkS")
		)
		(fp_line
			(start 0.7874 -0.4064)
			(end 0.7874 0.4064)
			(stroke
				(width 0.1524)
				(type default)
			)
			(layer "F.SilkS")
		)
		(fp_line
			(start -0.7874 0.4064)
			(end -0.7874 -0.4064)
			(stroke
				(width 0.1524)
				(type default)
			)
			(layer "F.SilkS")
		)
		(fp_line
			(start -0.7874 -0.4064)
			(end 0.7874 -0.4064)
			(stroke
				(width 0.1524)
				(type default)
			)
			(layer "F.SilkS")
		)
		(fp_line
			(start 0.67945 0.3048)
			(end 0.120396 0.3048)
			(stroke
				(width 0.1)
				(type default)
			)
			(layer "F.Fab")
		)
		(fp_line
			(start 0.67945 -0.3048)
			(end 0.67945 0.3048)
			(stroke
				(width 0.1)
				(type default)
			)
			(layer "F.Fab")
		)
		(fp_line
			(start 0.12065 -0.2794)
			(end 0.12065 -0.3048)
			(stroke
				(width 0.1)
				(type default)
			)
			(layer "F.Fab")
		)
		(fp_line
			(start 0.12065 -0.3048)
			(end 0.67945 -0.3048)
			(stroke
				(width 0.1)
				(type default)
			)
			(layer "F.Fab")
		)
		(fp_line
			(start 0.120396 0.3048)
			(end 0.120396 0.2794)
			(stroke
				(width 0.1)
				(type default)
			)
			(layer "F.Fab")
		)
		(fp_line
			(start 0.120396 0.2794)
			(end -0.12065 0.2794)
			(stroke
				(width 0.1)
				(type default)
			)
			(layer "F.Fab")
		)
		(fp_line
			(start -0.12065 0.3048)
			(end -0.67945 0.3048)
			(stroke
				(width 0.1)
				(type default)
			)
			(layer "F.Fab")
		)
		(fp_line
			(start -0.12065 0.2794)
			(end -0.12065 0.3048)
			(stroke
				(width 0.1)
				(type default)
			)
			(layer "F.Fab")
		)
		(fp_line
			(start -0.12065 -0.2794)
			(end 0.12065 -0.2794)
			(stroke
				(width 0.1)
				(type default)
			)
			(layer "F.Fab")
		)
		(fp_line
			(start -0.12065 -0.305054)
			(end -0.12065 -0.2794)
			(stroke
				(width 0.1)
				(type default)
			)
			(layer "F.Fab")
		)
		(fp_line
			(start -0.67945 0.3048)
			(end -0.67945 -0.305054)
			(stroke
				(width 0.1)
				(type default)
			)
			(layer "F.Fab")
		)
		(fp_line
			(start -0.67945 -0.305054)
			(end -0.12065 -0.305054)
			(stroke
				(width 0.1)
				(type default)
			)
			(layer "F.Fab")
		)
		(pad "1" smd circle
			(at -0.40005 0 180)
			(size 0 0)
			(layers "F.Cu" "F.Mask" "F.Paste")
			(net "FM_SWB_PWR_EN_R")
		)
		(pad "2" smd circle
			(at 0.40005 0 180)
			(size 0 0)
			(layers "F.Cu" "F.Mask" "F.Paste")
			(net "GND")
		)
	)
	(footprint ""
		(layer "F.Cu")
		(at 24.069802 -412.450534 180)
		(property "Reference" "R3473"
			(at 0 0 180)
			(layer "F.SilkS")
			(hide yes)
			(effects
				(font
					(size 1.27 1.27)
				)
			)
		)
		(property "Value" ""
			(at 0 0 180)
			(layer "F.Fab")
			(effects
				(font
					(size 1.27 1.27)
				)
			)
		)
		(duplicate_pad_numbers_are_jumpers no)
		(fp_line
			(start 0.7874 0.4064)
			(end -0.7874 0.4064)
			(stroke
				(width 0.1524)
				(type default)
			)
			(layer "F.SilkS")
		)
		(fp_line
			(start 0.7874 -0.4064)
			(end 0.7874 0.4064)
			(stroke
				(width 0.1524)
				(type default)
			)
			(layer "F.SilkS")
		)
		(fp_line
			(start -0.7874 0.4064)
			(end -0.7874 -0.4064)
			(stroke
				(width 0.1524)
				(type default)
			)
			(layer "F.SilkS")
		)
		(fp_line
			(start -0.7874 -0.4064)
			(end 0.7874 -0.4064)
			(stroke
				(width 0.1524)
				(type default)
			)
			(layer "F.SilkS")
		)
		(fp_line
			(start 0.67945 0.3048)
			(end 0.120396 0.3048)
			(stroke
				(width 0.1)
				(type default)
			)
			(layer "F.Fab")
		)
		(fp_line
			(start 0.67945 -0.3048)
			(end 0.67945 0.3048)
			(stroke
				(width 0.1)
				(type default)
			)
			(layer "F.Fab")
		)
		(fp_line
			(start 0.12065 -0.2794)
			(end 0.12065 -0.3048)
			(stroke
				(width 0.1)
				(type default)
			)
			(layer "F.Fab")
		)
		(fp_line
			(start 0.12065 -0.3048)
			(end 0.67945 -0.3048)
			(stroke
				(width 0.1)
				(type default)
			)
			(layer "F.Fab")
		)
		(fp_line
			(start 0.120396 0.3048)
			(end 0.120396 0.2794)
			(stroke
				(width 0.1)
				(type default)
			)
			(layer "F.Fab")
		)
		(fp_line
			(start 0.120396 0.2794)
			(end -0.12065 0.2794)
			(stroke
				(width 0.1)
				(type default)
			)
			(layer "F.Fab")
		)
		(fp_line
			(start -0.12065 0.3048)
			(end -0.67945 0.3048)
			(stroke
				(width 0.1)
				(type default)
			)
			(layer "F.Fab")
		)
		(fp_line
			(start -0.12065 0.2794)
			(end -0.12065 0.3048)
			(stroke
				(width 0.1)
				(type default)
			)
			(layer "F.Fab")
		)
		(fp_line
			(start -0.12065 -0.2794)
			(end 0.12065 -0.2794)
			(stroke
				(width 0.1)
				(type default)
			)
			(layer "F.Fab")
		)
		(fp_line
			(start -0.12065 -0.305054)
			(end -0.12065 -0.2794)
			(stroke
				(width 0.1)
				(type default)
			)
			(layer "F.Fab")
		)
		(fp_line
			(start -0.67945 0.3048)
			(end -0.67945 -0.305054)
			(stroke
				(width 0.1)
				(type default)
			)
			(layer "F.Fab")
		)
		(fp_line
			(start -0.67945 -0.305054)
			(end -0.12065 -0.305054)
			(stroke
				(width 0.1)
				(type default)
			)
			(layer "F.Fab")
		)
		(pad "1" smd circle
			(at -0.40005 0 180)
			(size 0 0)
			(layers "F.Cu" "F.Mask" "F.Paste")
			(net "GPU_PRSNT_N")
		)
		(pad "2" smd circle
			(at 0.40005 0 180)
			(size 0 0)
			(layers "F.Cu" "F.Mask" "F.Paste")
			(net "GND")
		)
	)
)
